(kicad_pcb
	(version 20260206)
	(generator "pcbnew")
	(generator_version "10.0")
	(general
		(thickness 1.6)
		(legacy_teardrops no)
	)
	(paper "A4")
	(title_block
		(title "v1-chassis-manager — T6M_CM_d_v01_1031_1645.brd")
		(comment 1 "Open CloudServer (Microsoft) / footprints 744-750 of 2512")
	)
	(layers
		(0 "F.Cu" signal "TOP")
		(4 "In1.Cu" signal "GND1")
		(6 "In2.Cu" signal "IN1")
		(8 "In3.Cu" signal "VCC1")
		(10 "In4.Cu" signal "VCC2")
		(12 "In5.Cu" signal "GND2")
		(14 "In6.Cu" signal "IN2")
		(16 "In7.Cu" signal "IN3")
		(18 "In8.Cu" signal "GND3")
		(2 "B.Cu" signal "BOTTOM")
		(9 "F.Adhes" user "F.Adhesive")
		(11 "B.Adhes" user "B.Adhesive")
		(13 "F.Paste" user "Package Geometry/Pastemask Top")
		(15 "B.Paste" user "Package Geometry/Pastemask Bottom")
		(5 "F.SilkS" user "Ref Des/Silkscreen Top")
		(7 "B.SilkS" user "Ref Des/Silkscreen Bottom")
		(1 "F.Mask" user "Board Geometry/Soldermask Top")
		(3 "B.Mask" user "Board Geometry/Soldermask Bottom")
		(17 "Dwgs.User" user "User.Drawings")
		(19 "Cmts.User" user "User.Comments")
		(21 "Eco1.User" user "User.Eco1")
		(23 "Eco2.User" user "User.Eco2")
		(25 "Edge.Cuts" user "Board Geometry/Outline")
		(27 "Margin" user)
		(31 "F.CrtYd" user "Package Geometry/Place Bound Top")
		(29 "B.CrtYd" user "Package Geometry/Place Bound Bottom")
		(35 "F.Fab" user "Ref Des/Assembly Top")
		(33 "B.Fab" user "Ref Des/Assembly Bottom")
	)
	(footprint ""
		(layer "F.Cu")
		(at 109.095286 -125.189742 90)
		(property "Reference" "U124"
			(at -0.399542 4.7244 90)
			(unlocked yes)
			(layer "F.SilkS")
			(effects
				(font
					(size 0.7874 0.5842)
					(thickness 0.1524)
				)
				(justify left)
			)
		)
		(property "Value" ""
			(at 0 0 90)
			(layer "F.Fab")
			(effects
				(font
					(size 1.27 1.27)
				)
			)
		)
		(duplicate_pad_numbers_are_jumpers no)
		(fp_line
			(start 2.649982 -3.10007)
			(end 2.649982 3.10007)
			(stroke
				(width 0.1524)
				(type default)
			)
			(layer "F.SilkS")
		)
		(fp_line
			(start 2.413 -3.10007)
			(end 2.649982 -3.10007)
			(stroke
				(width 0.1524)
				(type default)
			)
			(layer "F.SilkS")
		)
		(fp_line
			(start 1.143 -3.10007)
			(end 1.397 -3.10007)
			(stroke
				(width 0.1524)
				(type default)
			)
			(layer "F.SilkS")
		)
		(fp_line
			(start -0.127 -3.10007)
			(end 0.127 -3.10007)
			(stroke
				(width 0.1524)
				(type default)
			)
			(layer "F.SilkS")
		)
		(fp_line
			(start -1.397 -3.10007)
			(end -1.143 -3.10007)
			(stroke
				(width 0.1524)
				(type default)
			)
			(layer "F.SilkS")
		)
		(fp_line
			(start -2.649982 -3.10007)
			(end -2.413 -3.10007)
			(stroke
				(width 0.1524)
				(type default)
			)
			(layer "F.SilkS")
		)
		(fp_line
			(start 2.649982 3.10007)
			(end 2.413 3.10007)
			(stroke
				(width 0.1524)
				(type default)
			)
			(layer "F.SilkS")
		)
		(fp_line
			(start 1.143 3.10007)
			(end 1.397 3.10007)
			(stroke
				(width 0.1524)
				(type default)
			)
			(layer "F.SilkS")
		)
		(fp_line
			(start -0.127 3.10007)
			(end 0.127 3.10007)
			(stroke
				(width 0.1524)
				(type default)
			)
			(layer "F.SilkS")
		)
		(fp_line
			(start -1.397 3.10007)
			(end -1.143 3.10007)
			(stroke
				(width 0.1524)
				(type default)
			)
			(layer "F.SilkS")
		)
		(fp_line
			(start -2.413 3.10007)
			(end -2.649982 3.10007)
			(stroke
				(width 0.1524)
				(type default)
			)
			(layer "F.SilkS")
		)
		(fp_line
			(start -2.649982 3.10007)
			(end -2.649982 -3.10007)
			(stroke
				(width 0.1524)
				(type default)
			)
			(layer "F.SilkS")
		)
		(fp_poly
			(pts
				(xy -2.693416 3.52044) (xy -3.201416 4.53644) (xy -2.185416 4.53644)
			)
			(stroke
				(width 0)
				(type default)
			)
			(fill yes)
			(layer "F.SilkS")
		)
		(fp_poly
			(pts
				(xy -2.649982 3.10007) (xy -2.3368 3.10007) (xy -2.3368 3.5814) (xy 2.3368 3.5814) (xy 2.3368 3.10007)
				(xy 2.649982 3.10007) (xy 2.649982 -3.10007) (xy 2.3368 -3.10007) (xy 2.3368 -3.5814) (xy -2.3368 -3.5814)
				(xy -2.3368 -3.10007) (xy -2.649982 -3.10007)
			)
			(stroke
				(width 0)
				(type default)
			)
			(fill no)
			(layer "F.CrtYd")
		)
		(fp_line
			(start 2.649982 -3.10007)
			(end 2.649982 3.10007)
			(stroke
				(width 0.1)
				(type default)
			)
			(layer "F.Fab")
		)
		(fp_line
			(start -2.649982 -3.10007)
			(end 2.649982 -3.10007)
			(stroke
				(width 0.1)
				(type default)
			)
			(layer "F.Fab")
		)
		(fp_line
			(start 2.649982 3.10007)
			(end -2.649982 3.10007)
			(stroke
				(width 0.1)
				(type default)
			)
			(layer "F.Fab")
		)
		(fp_line
			(start -2.649982 3.10007)
			(end -2.649982 -3.10007)
			(stroke
				(width 0.1)
				(type default)
			)
			(layer "F.Fab")
		)
		(pad "1" smd rect
			(at -1.905 3.0099 90)
			(size 0.762 1.0414)
			(layers "F.Cu" "F.Mask" "F.Paste")
			(net "VR_PVCCP_NODE1_UGATE1")
		)
		(pad "2" smd rect
			(at -0.635 3.0099 90)
			(size 0.762 1.0414)
			(layers "F.Cu" "F.Mask" "F.Paste")
			(net "SW_VR_PVCCP_NODE1_VIN_FLT")
		)
		(pad "3" smd rect
			(at 0.635 3.0099 90)
			(size 0.762 1.0414)
			(layers "F.Cu" "F.Mask" "F.Paste")
			(net "SW_VR_PVCCP_NODE1_VIN_FLT")
		)
		(pad "4" smd rect
			(at 1.905 3.0099 90)
			(size 0.762 1.0414)
			(layers "F.Cu" "F.Mask" "F.Paste")
			(net "SW_VR_PVCCP_NODE1_VIN_FLT")
		)
		(pad "5" smd rect
			(at 1.905 -3.0099 90)
			(size 0.762 1.0414)
			(layers "F.Cu" "F.Mask" "F.Paste")
			(net "GND")
		)
		(pad "6" smd rect
			(at 0.635 -3.0099 90)
			(size 0.762 1.0414)
			(layers "F.Cu" "F.Mask" "F.Paste")
			(net "GND")
		)
		(pad "7" smd rect
			(at -0.635 -3.0099 90)
			(size 0.762 1.0414)
			(layers "F.Cu" "F.Mask" "F.Paste")
			(net "GND")
		)
		(pad "8" smd rect
			(at -1.905 -3.0099 90)
			(size 0.762 1.0414)
			(layers "F.Cu" "F.Mask" "F.Paste")
			(net "VR_PVCCP_NODE1_LGATE1")
		)
		(pad "D1_EP" smd rect
			(at 0 1.700022 180)
			(size 0.8128 4.2164)
			(layers "F.Cu" "F.Mask" "F.Paste")
			(net "SW_VR_PVCCP_NODE1_VIN_FLT")
		)
		(pad "S1/D2_EP" smd rect
			(at 0 -0.649986)
			(size 2.921 4.2164)
			(layers "F.Cu" "F.Mask" "F.Paste")
			(net "VR_PVCCP_NODE1_PHASE1")
		)
		(zone
			(layer "F.Cu")
			(hatch none 0.5)
			(connect_pads
				(clearance 0)
			)
			(min_thickness 0.25)
			(keepout
				(tracks allowed)
				(vias not_allowed)
				(pads allowed)
				(copperpour not_allowed)
				(footprints allowed)
			)
			(placement
				(enabled no)
				(sheetname "")
			)
			(fill
				(thermal_gap 0.5)
				(thermal_bridge_width 0.5)
				(island_removal_mode 0)
			)
			(polygon
				(pts
					(xy 110.822486 -122.700542) (xy 110.822486 -123.005342) (xy 111.279686 -123.005342) (xy 111.279686 -127.374142)
					(xy 110.314486 -127.374142) (xy 110.314486 -123.005342) (xy 110.797086 -123.005342) (xy 110.797086 -122.548142)
					(xy 108.409486 -122.548142) (xy 108.409486 -123.005342) (xy 109.984286 -123.005342) (xy 109.984286 -127.374142)
					(xy 106.910886 -127.374142) (xy 106.910886 -123.005342) (xy 108.384086 -123.005342) (xy 108.384086 -122.548142)
					(xy 106.682286 -122.548142) (xy 106.682286 -127.831342) (xy 111.508286 -127.831342) (xy 111.508286 -122.548142)
					(xy 110.822486 -122.548142)
				)
			)
		)
	)
	(footprint ""
		(layer "F.Cu")
		(at 87.887048 -128.998726 -90)
		(property "Reference" "R1256"
			(at 2.760218 -2.689098 90)
			(unlocked yes)
			(layer "F.SilkS")
			(effects
				(font
					(size 0.7874 0.5842)
					(thickness 0.1524)
				)
				(justify left)
			)
		)
		(property "Value" ""
			(at 0 0 270)
			(layer "F.Fab")
			(effects
				(font
					(size 1.27 1.27)
				)
			)
		)
		(duplicate_pad_numbers_are_jumpers no)
		(fp_line
			(start -0.7874 0.4064)
			(end -0.7874 -0.4064)
			(stroke
				(width 0.1524)
				(type default)
			)
			(layer "F.SilkS")
		)
		(fp_line
			(start 0.7874 0.4064)
			(end -0.7874 0.4064)
			(stroke
				(width 0.1524)
				(type default)
			)
			(layer "F.SilkS")
		)
		(fp_line
			(start -0.7874 -0.4064)
			(end 0.7874 -0.4064)
			(stroke
				(width 0.1524)
				(type default)
			)
			(layer "F.SilkS")
		)
		(fp_line
			(start 0.7874 -0.4064)
			(end 0.7874 0.4064)
			(stroke
				(width 0.1524)
				(type default)
			)
			(layer "F.SilkS")
		)
		(fp_poly
			(pts
				(xy -0.508 0.2794) (xy -0.508 0.2286) (xy -0.635 0.2286) (xy -0.635 -0.254) (xy -0.5334 -0.254)
				(xy -0.5334 -0.2794) (xy 0.5334 -0.2794) (xy 0.5334 -0.254) (xy 0.635 -0.254) (xy 0.635 0.254) (xy 0.5334 0.254)
				(xy 0.5334 0.2794)
			)
			(stroke
				(width 0)
				(type default)
			)
			(fill no)
			(layer "F.CrtYd")
		)
		(pad "1" smd rect
			(at 0.40005 0 270)
			(size 0.4572 0.508)
			(layers "F.Cu" "F.Mask" "F.Paste")
			(net "PORT80_LOUT4")
		)
		(pad "2" smd rect
			(at -0.40005 0 270)
			(size 0.4572 0.508)
			(layers "F.Cu" "F.Mask" "F.Paste")
			(net "N53313513")
		)
	)
	(footprint ""
		(layer "F.Cu")
		(at 94.451932 -175.322992)
		(property "Reference" "R739"
			(at 86.67369 74.174096 0)
			(unlocked yes)
			(layer "F.SilkS")
			(effects
				(font
					(size 0.7874 0.5842)
					(thickness 0.1524)
				)
				(justify left)
			)
		)
		(property "Value" ""
			(at 0 0 0)
			(layer "F.Fab")
			(effects
				(font
					(size 1.27 1.27)
				)
			)
		)
		(duplicate_pad_numbers_are_jumpers no)
		(fp_line
			(start -0.7874 -0.4064)
			(end 0.7874 -0.4064)
			(stroke
				(width 0.1524)
				(type default)
			)
			(layer "F.SilkS")
		)
		(fp_line
			(start -0.7874 0.4064)
			(end -0.7874 -0.4064)
			(stroke
				(width 0.1524)
				(type default)
			)
			(layer "F.SilkS")
		)
		(fp_line
			(start 0.7874 -0.4064)
			(end 0.7874 0.4064)
			(stroke
				(width 0.1524)
				(type default)
			)
			(layer "F.SilkS")
		)
		(fp_line
			(start 0.7874 0.4064)
			(end -0.7874 0.4064)
			(stroke
				(width 0.1524)
				(type default)
			)
			(layer "F.SilkS")
		)
		(fp_poly
			(pts
				(xy -0.508 0.2794) (xy -0.508 0.2286) (xy -0.635 0.2286) (xy -0.635 -0.254) (xy -0.5334 -0.254)
				(xy -0.5334 -0.2794) (xy 0.5334 -0.2794) (xy 0.5334 -0.254) (xy 0.635 -0.254) (xy 0.635 0.254) (xy 0.5334 0.254)
				(xy 0.5334 0.2794)
			)
			(stroke
				(width 0)
				(type default)
			)
			(fill no)
			(layer "F.CrtYd")
		)
		(pad "1" smd rect
			(at 0.40005 0)
			(size 0.4572 0.508)
			(layers "F.Cu" "F.Mask" "F.Paste")
			(net "N21698906")
		)
		(pad "2" smd rect
			(at -0.40005 0)
			(size 0.4572 0.508)
			(layers "F.Cu" "F.Mask" "F.Paste")
			(net "P3V3_NODE1")
		)
	)
	(footprint ""
		(layer "F.Cu")
		(at 105.947718 -151.7142)
		(property "Reference" "PR15"
			(at -2.05486 4.593082 0)
			(unlocked yes)
			(layer "F.SilkS")
			(effects
				(font
					(size 0.635 0.4064)
					(thickness 0.1524)
				)
				(justify left)
			)
		)
		(property "Value" ""
			(at 0 0 0)
			(layer "F.Fab")
			(effects
				(font
					(size 1.27 1.27)
				)
			)
		)
		(duplicate_pad_numbers_are_jumpers no)
		(fp_line
			(start -0.7874 -0.4064)
			(end 0.7874 -0.4064)
			(stroke
				(width 0.1524)
				(type default)
			)
			(layer "F.SilkS")
		)
		(fp_line
			(start -0.7874 0.4064)
			(end -0.7874 -0.4064)
			(stroke
				(width 0.1524)
				(type default)
			)
			(layer "F.SilkS")
		)
		(fp_line
			(start 0.7874 -0.4064)
			(end 0.7874 0.4064)
			(stroke
				(width 0.1524)
				(type default)
			)
			(layer "F.SilkS")
		)
		(fp_line
			(start 0.7874 0.4064)
			(end -0.7874 0.4064)
			(stroke
				(width 0.1524)
				(type default)
			)
			(layer "F.SilkS")
		)
		(fp_poly
			(pts
				(xy -0.508 0.2794) (xy -0.508 0.2286) (xy -0.635 0.2286) (xy -0.635 -0.254) (xy -0.5334 -0.254)
				(xy -0.5334 -0.2794) (xy 0.5334 -0.2794) (xy 0.5334 -0.254) (xy 0.635 -0.254) (xy 0.635 0.254) (xy 0.5334 0.254)
				(xy 0.5334 0.2794)
			)
			(stroke
				(width 0)
				(type default)
			)
			(fill no)
			(layer "F.CrtYd")
		)
		(pad "1" smd rect
			(at 0.40005 0)
			(size 0.4572 0.508)
			(layers "F.Cu" "F.Mask" "F.Paste")
			(net "P1V8_STB_NODE1_FB")
		)
		(pad "2" smd rect
			(at -0.40005 0)
			(size 0.4572 0.508)
			(layers "F.Cu" "F.Mask" "F.Paste")
			(net "P1V8_STB_NODE1")
		)
	)
	(footprint ""
		(layer "F.Cu")
		(at 155.444952 -103.99395 -90)
		(property "Reference" "R520"
			(at 0.801878 2.11963 90)
			(unlocked yes)
			(layer "F.SilkS")
			(effects
				(font
					(size 0.7874 0.5842)
					(thickness 0.1524)
				)
				(justify left)
			)
		)
		(property "Value" ""
			(at 0 0 270)
			(layer "F.Fab")
			(effects
				(font
					(size 1.27 1.27)
				)
			)
		)
		(duplicate_pad_numbers_are_jumpers no)
		(fp_line
			(start -0.7874 0.4064)
			(end -0.7874 -0.4064)
			(stroke
				(width 0.1524)
				(type default)
			)
			(layer "F.SilkS")
		)
		(fp_line
			(start 0.7874 0.4064)
			(end -0.7874 0.4064)
			(stroke
				(width 0.1524)
				(type default)
			)
			(layer "F.SilkS")
		)
		(fp_line
			(start -0.7874 -0.4064)
			(end 0.7874 -0.4064)
			(stroke
				(width 0.1524)
				(type default)
			)
			(layer "F.SilkS")
		)
		(fp_line
			(start 0.7874 -0.4064)
			(end 0.7874 0.4064)
			(stroke
				(width 0.1524)
				(type default)
			)
			(layer "F.SilkS")
		)
		(fp_poly
			(pts
				(xy -0.508 0.2794) (xy -0.508 0.2286) (xy -0.635 0.2286) (xy -0.635 -0.254) (xy -0.5334 -0.254)
				(xy -0.5334 -0.2794) (xy 0.5334 -0.2794) (xy 0.5334 -0.254) (xy 0.635 -0.254) (xy 0.635 0.254) (xy 0.5334 0.254)
				(xy 0.5334 0.2794)
			)
			(stroke
				(width 0)
				(type default)
			)
			(fill no)
			(layer "F.CrtYd")
		)
		(pad "1" smd rect
			(at 0.40005 0 270)
			(size 0.4572 0.508)
			(layers "F.Cu" "F.Mask" "F.Paste")
			(net "IRQ_LVC3_CPU_NODE1_WAKE_L")
		)
		(pad "2" smd rect
			(at -0.40005 0 270)
			(size 0.4572 0.508)
			(layers "F.Cu" "F.Mask" "F.Paste")
			(net "USB_WAKE_N")
		)
	)
	(footprint ""
		(layer "F.Cu")
		(at 184.3786 -181.8132)
		(property "Reference" "R1320"
			(at 9.2964 17.09547 0)
			(unlocked yes)
			(layer "F.SilkS")
			(effects
				(font
					(size 0.7874 0.5842)
					(thickness 0.1524)
				)
				(justify left)
			)
		)
		(property "Value" ""
			(at 0 0 0)
			(layer "F.Fab")
			(effects
				(font
					(size 1.27 1.27)
				)
			)
		)
		(duplicate_pad_numbers_are_jumpers no)
		(fp_line
			(start -0.7874 -0.4064)
			(end 0.7874 -0.4064)
			(stroke
				(width 0.1524)
				(type default)
			)
			(layer "F.SilkS")
		)
		(fp_line
			(start -0.7874 0.4064)
			(end -0.7874 -0.4064)
			(stroke
				(width 0.1524)
				(type default)
			)
			(layer "F.SilkS")
		)
		(fp_line
			(start 0.7874 -0.4064)
			(end 0.7874 0.4064)
			(stroke
				(width 0.1524)
				(type default)
			)
			(layer "F.SilkS")
		)
		(fp_line
			(start 0.7874 0.4064)
			(end -0.7874 0.4064)
			(stroke
				(width 0.1524)
				(type default)
			)
			(layer "F.SilkS")
		)
		(fp_poly
			(pts
				(xy -0.508 0.2794) (xy -0.508 0.2286) (xy -0.635 0.2286) (xy -0.635 -0.254) (xy -0.5334 -0.254)
				(xy -0.5334 -0.2794) (xy 0.5334 -0.2794) (xy 0.5334 -0.254) (xy 0.635 -0.254) (xy 0.635 0.254) (xy 0.5334 0.254)
				(xy 0.5334 0.2794)
			)
			(stroke
				(width 0)
				(type default)
			)
			(fill no)
			(layer "F.CrtYd")
		)
		(pad "1" smd rect
			(at 0.40005 0)
			(size 0.4572 0.508)
			(layers "F.Cu" "F.Mask" "F.Paste")
			(net "POWER_SW3_PWR_CTR_12V")
		)
		(pad "2" smd rect
			(at -0.40005 0)
			(size 0.4572 0.508)
			(layers "F.Cu" "F.Mask" "F.Paste")
			(net "POWER_SW3_PWR_CTR_12V_R")
		)
	)
	(footprint ""
		(layer "F.Cu")
		(at 51.03114 -163.89985 90)
		(property "Reference" "R538"
			(at -131.03606 -3.526028 90)
			(unlocked yes)
			(layer "F.SilkS")
			(effects
				(font
					(size 0.7874 0.5842)
					(thickness 0.1524)
				)
				(justify left)
			)
		)
		(property "Value" ""
			(at 0 0 90)
			(layer "F.Fab")
			(effects
				(font
					(size 1.27 1.27)
				)
			)
		)
		(duplicate_pad_numbers_are_jumpers no)
		(fp_line
			(start 0.7874 -0.4064)
			(end 0.7874 0.4064)
			(stroke
				(width 0.1524)
				(type default)
			)
			(layer "F.SilkS")
		)
		(fp_line
			(start -0.7874 -0.4064)
			(end 0.7874 -0.4064)
			(stroke
				(width 0.1524)
				(type default)
			)
			(layer "F.SilkS")
		)
		(fp_line
			(start 0.7874 0.4064)
			(end -0.7874 0.4064)
			(stroke
				(width 0.1524)
				(type default)
			)
			(layer "F.SilkS")
		)
		(fp_line
			(start -0.7874 0.4064)
			(end -0.7874 -0.4064)
			(stroke
				(width 0.1524)
				(type default)
			)
			(layer "F.SilkS")
		)
		(fp_poly
			(pts
				(xy -0.508 0.2794) (xy -0.508 0.2286) (xy -0.635 0.2286) (xy -0.635 -0.254) (xy -0.5334 -0.254)
				(xy -0.5334 -0.2794) (xy 0.5334 -0.2794) (xy 0.5334 -0.254) (xy 0.635 -0.254) (xy 0.635 0.254) (xy 0.5334 0.254)
				(xy 0.5334 0.2794)
			)
			(stroke
				(width 0)
				(type default)
			)
			(fill no)
			(layer "F.CrtYd")
		)
		(pad "1" smd rect
			(at 0.40005 0 90)
			(size 0.4572 0.508)
			(layers "F.Cu" "F.Mask" "F.Paste")
			(net "P3V3_NODE1")
		)
		(pad "2" smd rect
			(at -0.40005 0 90)
			(size 0.4572 0.508)
			(layers "F.Cu" "F.Mask" "F.Paste")
			(net "SMB_LAN1_ALT_N")
		)
	)
)
